FILE_TYPE = CONNECTIVITY;
{Allegro Design Entry HDL 17.2-2016 S081 (4005846) 1/11/2022}
"PAGE_NUMBER" = 310;
0"NC";
1"T1_GND\g";
2"T1_GND\g";
3"T1_GND\g";
4"T1_GND\g";
5"T1_GND\g";
6"T1_GND\g";
7"T1_GND\g";
8"T1_GND\g";
9"T1_GND\g";
10"T1_GND\g";
11"T1_GND\g";
12"T1_GND\g";
13"UN$310$TPTDR4PFTS$I15$S2";
14"UN$310$TPTDR4PFTS$I19$S2";
15"UN$310$TPTDR4PFTS$I15$S1";
16"UN$310$TPTDR4PFTS$I19$S1";
17"UN$310$TPTDR4PFTS$I20$S2";
18"UN$310$TPTDR4PFTS$I20$S1";
19"UN$310$TPTDR4PFTS$I10$S2";
20"UN$310$TPTDR4PFTS$I5$S1";
21"UN$310$TPTDR4PFTS$I7$S2";
22"UN$310$TPTDR4PFTS$I7$S1";
23"UN$310$TPTDR4PFTS$I10$S1";
24"UN$310$TPTDR4PFTS$I5$S2";
%"UNIVERSAL_GND"
"1","(-2325,-650)","0","logical_power","I1";
;
HDL_POWER"T1_GND"
CDS_LIB"logical_power";
"A"1;
%"TP_TDR_4P_FTS"
"1","(-575,1025)","4","pure_quanta","I10";
;
PART_NUMBER"TP15"
VALUE"TP_TDR_4P_DIP"
PACK_TYPE"TH"
MATERIAL"EMPTY"
$LOCATION"X42"
NEEDS_NO_SIZE"TRUE"
CDS_LIB"pure_quanta"
CDS_LOCATION"X42"
$SEC"1"
CDS_SEC"1";
"S1"
$PN"1"23;
"P2 \B"
$PN"3"7;
"S2"
$PN"4"19;
"P1 \B"
$PN"2"7;
%"UNIVERSAL_GND"
"1","(-175,-650)","0","logical_power","I11";
;
HDL_POWER"T1_GND"
CDS_LIB"logical_power";
"A"5;
%"UNIVERSAL_GND"
"1","(-175,125)","0","logical_power","I12";
;
HDL_POWER"T1_GND"
CDS_LIB"logical_power";
"A"6;
%"UNIVERSAL_GND"
"1","(-175,800)","0","logical_power","I13";
;
HDL_POWER"T1_GND"
CDS_LIB"logical_power";
"A"7;
%"UNIVERSAL_GND"
"1","(-175,1575)","0","logical_power","I14";
;
HDL_POWER"T1_GND"
CDS_LIB"logical_power";
"A"8;
%"TP_TDR_4P_FTS"
"1","(-575,1800)","4","pure_quanta","I15";
;
PART_NUMBER"TP15"
MATERIAL"EMPTY"
PACK_TYPE"TH"
VALUE"TP_TDR_4P_DIP"
$LOCATION"X41"
NEEDS_NO_SIZE"TRUE"
CDS_LIB"pure_quanta"
CDS_LOCATION"X41"
$SEC"1"
CDS_SEC"1";
"S1"
$PN"1"15;
"P2 \B"
$PN"3"8;
"S2"
$PN"4"13;
"P1 \B"
$PN"2"8;
%"TP_TDR_4P_FTS"
"1","(-1900,1800)","0","pure_quanta","I16";
;
PART_NUMBER"TP15"
MATERIAL"EMPTY"
PACK_TYPE"TH"
VALUE"TP_TDR_4P_DIP"
$LOCATION"X35"
NEEDS_NO_SIZE"TRUE"
CDS_LIB"pure_quanta"
CDS_LOCATION"X35"
$SEC"1"
CDS_SEC"1";
"S1"
$PN"1"13;
"P2 \B"
$PN"3"4;
"S2"
$PN"4"15;
"P1 \B"
$PN"2"4;
%"UNIVERSAL_GND"
"1","(-2325,2350)","0","logical_power","I17";
;
HDL_POWER"T1_GND"
CDS_LIB"logical_power";
"A"9;
%"UNIVERSAL_GND"
"1","(-2325,3125)","0","logical_power","I18";
;
HDL_POWER"T1_GND"
CDS_LIB"logical_power";
"A"10;
%"TP_TDR_4P_FTS"
"1","(-1900,2575)","0","pure_quanta","I19";
;
PART_NUMBER"TP15"
MATERIAL"EMPTY"
PACK_TYPE"TH"
VALUE"TP_TDR_4P_DIP"
$LOCATION"X34"
NEEDS_NO_SIZE"TRUE"
CDS_LIB"pure_quanta"
CDS_LOCATION"X34"
$SEC"1"
CDS_SEC"1";
"S1"
$PN"1"16;
"P2 \B"
$PN"3"9;
"S2"
$PN"4"14;
"P1 \B"
$PN"2"9;
%"UNIVERSAL_GND"
"1","(-2325,125)","0","logical_power","I2";
;
HDL_POWER"T1_GND"
CDS_LIB"logical_power";
"A"2;
%"TP_TDR_4P_FTS"
"1","(-1900,3350)","0","pure_quanta","I20";
;
PART_NUMBER"TP15"
MATERIAL"EMPTY"
PACK_TYPE"TH"
VALUE"TP_TDR_4P_DIP"
$LOCATION"X33"
NEEDS_NO_SIZE"TRUE"
CDS_LIB"pure_quanta"
CDS_LOCATION"X33"
$SEC"1"
CDS_SEC"1";
"S1"
$PN"1"18;
"P2 \B"
$PN"3"10;
"S2"
$PN"4"17;
"P1 \B"
$PN"2"10;
%"TP_TDR_4P_FTS"
"1","(-575,2575)","4","pure_quanta","I21";
;
PART_NUMBER"TP15"
VALUE"TP_TDR_4P_DIP"
MATERIAL"EMPTY"
PACK_TYPE"TH"
$LOCATION"X40"
NEEDS_NO_SIZE"TRUE"
CDS_LIB"pure_quanta"
CDS_LOCATION"X40"
$SEC"1"
CDS_SEC"1";
"S1"
$PN"1"14;
"P2 \B"
$PN"3"11;
"S2"
$PN"4"16;
"P1 \B"
$PN"2"11;
%"TP_TDR_4P_FTS"
"1","(-575,3350)","4","pure_quanta","I22";
;
PART_NUMBER"TP15"
VALUE"TP_TDR_4P_DIP"
PACK_TYPE"TH"
MATERIAL"EMPTY"
$LOCATION"X39"
NEEDS_NO_SIZE"TRUE"
CDS_LIB"pure_quanta"
CDS_LOCATION"X39"
$SEC"1"
CDS_SEC"1";
"S1"
$PN"1"17;
"P2 \B"
$PN"3"12;
"S2"
$PN"4"18;
"P1 \B"
$PN"2"12;
%"UNIVERSAL_GND"
"1","(-175,2350)","0","logical_power","I23";
;
HDL_POWER"T1_GND"
CDS_LIB"logical_power";
"A"11;
%"UNIVERSAL_GND"
"1","(-175,3125)","0","logical_power","I24";
;
HDL_POWER"T1_GND"
CDS_LIB"logical_power";
"A"12;
%"UNIVERSAL_GND"
"1","(-2325,800)","0","logical_power","I3";
;
HDL_POWER"T1_GND"
CDS_LIB"logical_power";
"A"3;
%"UNIVERSAL_GND"
"1","(-2325,1575)","0","logical_power","I4";
;
HDL_POWER"T1_GND"
CDS_LIB"logical_power";
"A"4;
%"TP_TDR_4P_FTS"
"1","(-1900,-425)","0","pure_quanta","I5";
;
PART_NUMBER"TP15"
VALUE"TP_TDR_4P_DIP"
PACK_TYPE"TH"
MATERIAL"EMPTY"
$LOCATION"X38"
NEEDS_NO_SIZE"TRUE"
CDS_LIB"pure_quanta"
CDS_LOCATION"X38"
$SEC"1"
CDS_SEC"1";
"S1"
$PN"1"20;
"P2 \B"
$PN"3"1;
"S2"
$PN"4"24;
"P1 \B"
$PN"2"1;
%"TP_TDR_4P_FTS"
"1","(-575,-425)","4","pure_quanta","I6";
;
PART_NUMBER"TP15"
PACK_TYPE"TH"
MATERIAL"EMPTY"
VALUE"TP_TDR_4P_DIP"
$LOCATION"X44"
NEEDS_NO_SIZE"TRUE"
CDS_LIB"pure_quanta"
CDS_LOCATION"X44"
$SEC"1"
CDS_SEC"1";
"S1"
$PN"1"24;
"P2 \B"
$PN"3"5;
"S2"
$PN"4"20;
"P1 \B"
$PN"2"5;
%"TP_TDR_4P_FTS"
"1","(-1900,350)","0","pure_quanta","I7";
;
PART_NUMBER"TP15"
MATERIAL"EMPTY"
PACK_TYPE"TH"
VALUE"TP_TDR_4P_DIP"
$LOCATION"X37"
NEEDS_NO_SIZE"TRUE"
CDS_LIB"pure_quanta"
CDS_LOCATION"X37"
$SEC"1"
CDS_SEC"1";
"S1"
$PN"1"22;
"P2 \B"
$PN"3"2;
"S2"
$PN"4"21;
"P1 \B"
$PN"2"2;
%"TP_TDR_4P_FTS"
"1","(-1900,1025)","0","pure_quanta","I8";
;
PART_NUMBER"TP15"
VALUE"TP_TDR_4P_DIP"
PACK_TYPE"TH"
MATERIAL"EMPTY"
$LOCATION"X36"
NEEDS_NO_SIZE"TRUE"
CDS_LIB"pure_quanta"
CDS_LOCATION"X36"
$SEC"1"
CDS_SEC"1";
"S1"
$PN"1"19;
"P2 \B"
$PN"3"3;
"S2"
$PN"4"23;
"P1 \B"
$PN"2"3;
%"TP_TDR_4P_FTS"
"1","(-575,350)","4","pure_quanta","I9";
;
PART_NUMBER"TP15"
VALUE"TP_TDR_4P_DIP"
MATERIAL"EMPTY"
PACK_TYPE"TH"
$LOCATION"X43"
NEEDS_NO_SIZE"TRUE"
CDS_LIB"pure_quanta"
CDS_LOCATION"X43"
$SEC"1"
CDS_SEC"1";
"S1"
$PN"1"21;
"P2 \B"
$PN"3"6;
"S2"
$PN"4"22;
"P1 \B"
$PN"2"6;
END.
